(kicad_pcb
	(version 20260206)
	(generator "pcbnew")
	(generator_version "10.0")
	(general
		(thickness 1.6)
		(legacy_teardrops no)
	)
	(paper "A4")
	(title_block
		(title "03242023_DA0F0TMBIJ0_F0T_Motherboard_J_brd_V01_OCP.brd")
		(comment 1 "Grand Teton / footprints 5419-5424 of 6105")
	)
	(layers
		(0 "F.Cu" signal "TOP")
		(4 "In1.Cu" signal "GND")
		(6 "In2.Cu" signal "IN1")
		(8 "In3.Cu" signal "GND1")
		(10 "In4.Cu" signal "IN2")
		(12 "In5.Cu" signal "GND2")
		(14 "In6.Cu" signal "IN3")
		(16 "In7.Cu" signal "GND3")
		(18 "In8.Cu" signal "VCC")
		(20 "In9.Cu" signal "VCC1")
		(22 "In10.Cu" signal "GND4")
		(24 "In11.Cu" signal "IN4")
		(26 "In12.Cu" signal "GND5")
		(28 "In13.Cu" signal "IN5")
		(30 "In14.Cu" signal "GND6")
		(32 "In15.Cu" signal "IN6")
		(34 "In16.Cu" signal "GND7")
		(2 "B.Cu" signal "BOTTOM")
		(9 "F.Adhes" user "F.Adhesive")
		(11 "B.Adhes" user "B.Adhesive")
		(13 "F.Paste" user "Package Geometry/Pastemask Top")
		(15 "B.Paste" user "Package Geometry/Pastemask Bottom")
		(5 "F.SilkS" user "Ref Des/Silkscreen Top")
		(7 "B.SilkS" user "Ref Des/Silkscreen Bottom")
		(1 "F.Mask" user "Board Geometry/Soldermask Top")
		(3 "B.Mask" user "Board Geometry/Soldermask Bottom")
		(17 "Dwgs.User" user "User.Drawings")
		(19 "Cmts.User" user "User.Comments")
		(21 "Eco1.User" user "User.Eco1")
		(23 "Eco2.User" user "User.Eco2")
		(25 "Edge.Cuts" user "Board Geometry/Outline")
		(27 "Margin" user)
		(31 "F.CrtYd" user "Package Geometry/Place Bound Top")
		(29 "B.CrtYd" user "Package Geometry/Place Bound Bottom")
		(35 "F.Fab" user "Ref Des/Assembly Top")
		(33 "B.Fab" user "Ref Des/Assembly Bottom")
	)
	(footprint ""
		(layer "B.Cu")
		(at 186.055254 -19.417792 -90)
		(property "Reference" "R2257"
			(at 0 0 90)
			(layer "B.SilkS")
			(hide yes)
			(effects
				(font
					(size 1.27 1.27)
				)
				(justify mirror)
			)
		)
		(property "Value" ""
			(at 0 0 90)
			(layer "B.Fab")
			(effects
				(font
					(size 1.27 1.27)
				)
				(justify mirror)
			)
		)
		(duplicate_pad_numbers_are_jumpers no)
		(fp_line
			(start -0.7874 0.4064)
			(end 0.7874 0.4064)
			(stroke
				(width 0.1524)
				(type default)
			)
			(layer "B.SilkS")
		)
		(fp_line
			(start 0.7874 0.4064)
			(end 0.7874 -0.154686)
			(stroke
				(width 0.1524)
				(type default)
			)
			(layer "B.SilkS")
		)
		(fp_line
			(start -0.7874 -0.131826)
			(end -0.7874 0.4064)
			(stroke
				(width 0.1524)
				(type default)
			)
			(layer "B.SilkS")
		)
		(fp_line
			(start 0.534924 -0.4064)
			(end -0.318516 -0.4064)
			(stroke
				(width 0.1524)
				(type default)
			)
			(layer "B.SilkS")
		)
		(fp_line
			(start -0.67945 0.3048)
			(end -0.120396 0.3048)
			(stroke
				(width 0.1)
				(type default)
			)
			(layer "B.Fab")
		)
		(fp_line
			(start -0.120396 0.3048)
			(end -0.120396 0.2794)
			(stroke
				(width 0.1)
				(type default)
			)
			(layer "B.Fab")
		)
		(fp_line
			(start 0.12065 0.3048)
			(end 0.67945 0.3048)
			(stroke
				(width 0.1)
				(type default)
			)
			(layer "B.Fab")
		)
		(fp_line
			(start 0.67945 0.3048)
			(end 0.67945 -0.305054)
			(stroke
				(width 0.1)
				(type default)
			)
			(layer "B.Fab")
		)
		(fp_line
			(start -0.120396 0.2794)
			(end 0.12065 0.2794)
			(stroke
				(width 0.1)
				(type default)
			)
			(layer "B.Fab")
		)
		(fp_line
			(start 0.12065 0.2794)
			(end 0.12065 0.3048)
			(stroke
				(width 0.1)
				(type default)
			)
			(layer "B.Fab")
		)
		(fp_line
			(start -0.12065 -0.2794)
			(end -0.12065 -0.3048)
			(stroke
				(width 0.1)
				(type default)
			)
			(layer "B.Fab")
		)
		(fp_line
			(start 0.12065 -0.2794)
			(end -0.12065 -0.2794)
			(stroke
				(width 0.1)
				(type default)
			)
			(layer "B.Fab")
		)
		(fp_line
			(start -0.67945 -0.3048)
			(end -0.67945 0.3048)
			(stroke
				(width 0.1)
				(type default)
			)
			(layer "B.Fab")
		)
		(fp_line
			(start -0.12065 -0.3048)
			(end -0.67945 -0.3048)
			(stroke
				(width 0.1)
				(type default)
			)
			(layer "B.Fab")
		)
		(fp_line
			(start 0.12065 -0.305054)
			(end 0.12065 -0.2794)
			(stroke
				(width 0.1)
				(type default)
			)
			(layer "B.Fab")
		)
		(fp_line
			(start 0.67945 -0.305054)
			(end 0.12065 -0.305054)
			(stroke
				(width 0.1)
				(type default)
			)
			(layer "B.Fab")
		)
		(pad "1" smd circle
			(at 0.40005 0 90)
			(size 0 0)
			(layers "B.Cu" "B.Mask" "B.Paste")
			(net "USB2_7_R_DN")
		)
		(pad "2" smd circle
			(at -0.40005 0 90)
			(size 0 0)
			(layers "B.Cu" "B.Mask" "B.Paste")
			(net "USB2_7_DN")
		)
	)
	(footprint ""
		(layer "B.Cu")
		(at 369.117372 -184.400952 90)
		(property "Reference" "R965"
			(at 0 0 90)
			(layer "B.SilkS")
			(hide yes)
			(effects
				(font
					(size 1.27 1.27)
				)
				(justify mirror)
			)
		)
		(property "Value" ""
			(at 0 0 90)
			(layer "B.Fab")
			(effects
				(font
					(size 1.27 1.27)
				)
				(justify mirror)
			)
		)
		(duplicate_pad_numbers_are_jumpers no)
		(fp_line
			(start 0.7874 -0.4064)
			(end -0.7874 -0.4064)
			(stroke
				(width 0.1524)
				(type default)
			)
			(layer "B.SilkS")
		)
		(fp_line
			(start -0.7874 -0.4064)
			(end -0.7874 0.4064)
			(stroke
				(width 0.1524)
				(type default)
			)
			(layer "B.SilkS")
		)
		(fp_line
			(start 0.7874 0.4064)
			(end 0.7874 -0.4064)
			(stroke
				(width 0.1524)
				(type default)
			)
			(layer "B.SilkS")
		)
		(fp_line
			(start -0.7874 0.4064)
			(end 0.7874 0.4064)
			(stroke
				(width 0.1524)
				(type default)
			)
			(layer "B.SilkS")
		)
		(fp_line
			(start 0.67945 -0.305054)
			(end 0.12065 -0.305054)
			(stroke
				(width 0.1)
				(type default)
			)
			(layer "B.Fab")
		)
		(fp_line
			(start 0.12065 -0.305054)
			(end 0.12065 -0.2794)
			(stroke
				(width 0.1)
				(type default)
			)
			(layer "B.Fab")
		)
		(fp_line
			(start -0.12065 -0.3048)
			(end -0.67945 -0.3048)
			(stroke
				(width 0.1)
				(type default)
			)
			(layer "B.Fab")
		)
		(fp_line
			(start -0.67945 -0.3048)
			(end -0.67945 0.3048)
			(stroke
				(width 0.1)
				(type default)
			)
			(layer "B.Fab")
		)
		(fp_line
			(start 0.12065 -0.2794)
			(end -0.12065 -0.2794)
			(stroke
				(width 0.1)
				(type default)
			)
			(layer "B.Fab")
		)
		(fp_line
			(start -0.12065 -0.2794)
			(end -0.12065 -0.3048)
			(stroke
				(width 0.1)
				(type default)
			)
			(layer "B.Fab")
		)
		(fp_line
			(start 0.12065 0.2794)
			(end 0.12065 0.3048)
			(stroke
				(width 0.1)
				(type default)
			)
			(layer "B.Fab")
		)
		(fp_line
			(start -0.120396 0.2794)
			(end 0.12065 0.2794)
			(stroke
				(width 0.1)
				(type default)
			)
			(layer "B.Fab")
		)
		(fp_line
			(start 0.67945 0.3048)
			(end 0.67945 -0.305054)
			(stroke
				(width 0.1)
				(type default)
			)
			(layer "B.Fab")
		)
		(fp_line
			(start 0.12065 0.3048)
			(end 0.67945 0.3048)
			(stroke
				(width 0.1)
				(type default)
			)
			(layer "B.Fab")
		)
		(fp_line
			(start -0.120396 0.3048)
			(end -0.120396 0.2794)
			(stroke
				(width 0.1)
				(type default)
			)
			(layer "B.Fab")
		)
		(fp_line
			(start -0.67945 0.3048)
			(end -0.120396 0.3048)
			(stroke
				(width 0.1)
				(type default)
			)
			(layer "B.Fab")
		)
		(pad "1" smd circle
			(at 0.40005 0 270)
			(size 0 0)
			(layers "B.Cu" "B.Mask" "B.Paste")
			(net "P3V3_AUX")
		)
		(pad "2" smd circle
			(at -0.40005 0 270)
			(size 0 0)
			(layers "B.Cu" "B.Mask" "B.Paste")
			(net "SMB_PEHPCPU0_LVC3_SCL")
		)
	)
	(footprint ""
		(layer "B.Cu")
		(at 256.55397 -55.436262 180)
		(property "Reference" "R3941"
			(at 0 0 0)
			(layer "B.SilkS")
			(hide yes)
			(effects
				(font
					(size 1.27 1.27)
				)
				(justify mirror)
			)
		)
		(property "Value" ""
			(at 0 0 0)
			(layer "B.Fab")
			(effects
				(font
					(size 1.27 1.27)
				)
				(justify mirror)
			)
		)
		(duplicate_pad_numbers_are_jumpers no)
		(fp_line
			(start 0.7874 0.4064)
			(end 0.7874 -0.4064)
			(stroke
				(width 0.1524)
				(type default)
			)
			(layer "B.SilkS")
		)
		(fp_line
			(start 0.7874 -0.4064)
			(end -0.7874 -0.4064)
			(stroke
				(width 0.1524)
				(type default)
			)
			(layer "B.SilkS")
		)
		(fp_line
			(start -0.7874 0.4064)
			(end 0.7874 0.4064)
			(stroke
				(width 0.1524)
				(type default)
			)
			(layer "B.SilkS")
		)
		(fp_line
			(start -0.7874 -0.4064)
			(end -0.7874 0.4064)
			(stroke
				(width 0.1524)
				(type default)
			)
			(layer "B.SilkS")
		)
		(fp_line
			(start 0.67945 0.3048)
			(end 0.67945 -0.305054)
			(stroke
				(width 0.1)
				(type default)
			)
			(layer "B.Fab")
		)
		(fp_line
			(start 0.67945 -0.305054)
			(end 0.12065 -0.305054)
			(stroke
				(width 0.1)
				(type default)
			)
			(layer "B.Fab")
		)
		(fp_line
			(start 0.12065 0.3048)
			(end 0.67945 0.3048)
			(stroke
				(width 0.1)
				(type default)
			)
			(layer "B.Fab")
		)
		(fp_line
			(start 0.12065 0.2794)
			(end 0.12065 0.3048)
			(stroke
				(width 0.1)
				(type default)
			)
			(layer "B.Fab")
		)
		(fp_line
			(start 0.12065 -0.2794)
			(end -0.12065 -0.2794)
			(stroke
				(width 0.1)
				(type default)
			)
			(layer "B.Fab")
		)
		(fp_line
			(start 0.12065 -0.305054)
			(end 0.12065 -0.2794)
			(stroke
				(width 0.1)
				(type default)
			)
			(layer "B.Fab")
		)
		(fp_line
			(start -0.120396 0.3048)
			(end -0.120396 0.2794)
			(stroke
				(width 0.1)
				(type default)
			)
			(layer "B.Fab")
		)
		(fp_line
			(start -0.120396 0.2794)
			(end 0.12065 0.2794)
			(stroke
				(width 0.1)
				(type default)
			)
			(layer "B.Fab")
		)
		(fp_line
			(start -0.12065 -0.2794)
			(end -0.12065 -0.3048)
			(stroke
				(width 0.1)
				(type default)
			)
			(layer "B.Fab")
		)
		(fp_line
			(start -0.12065 -0.3048)
			(end -0.67945 -0.3048)
			(stroke
				(width 0.1)
				(type default)
			)
			(layer "B.Fab")
		)
		(fp_line
			(start -0.67945 0.3048)
			(end -0.120396 0.3048)
			(stroke
				(width 0.1)
				(type default)
			)
			(layer "B.Fab")
		)
		(fp_line
			(start -0.67945 -0.3048)
			(end -0.67945 0.3048)
			(stroke
				(width 0.1)
				(type default)
			)
			(layer "B.Fab")
		)
		(pad "1" smd rect
			(at 0.40005 0 180)
			(size 0.4572 0.508)
			(layers "B.Cu" "B.Mask" "B.Paste")
			(net "P12V_E1S_0_ISENSE_MAM_TIC")
		)
		(pad "2" smd rect
			(at -0.40005 0 180)
			(size 0.4572 0.508)
			(layers "B.Cu" "B.Mask" "B.Paste")
			(net "P12V_E1S_0_ISENSE_TIC")
		)
	)
	(footprint ""
		(layer "B.Cu")
		(at 19.760946 -319.268856 180)
		(property "Reference" "R900"
			(at 0 0 0)
			(layer "B.SilkS")
			(hide yes)
			(effects
				(font
					(size 1.27 1.27)
				)
				(justify mirror)
			)
		)
		(property "Value" ""
			(at 0 0 0)
			(layer "B.Fab")
			(effects
				(font
					(size 1.27 1.27)
				)
				(justify mirror)
			)
		)
		(duplicate_pad_numbers_are_jumpers no)
		(fp_line
			(start 0.7874 0.4064)
			(end 0.7874 -0.4064)
			(stroke
				(width 0.1524)
				(type default)
			)
			(layer "B.SilkS")
		)
		(fp_line
			(start 0.7874 -0.4064)
			(end -0.7874 -0.4064)
			(stroke
				(width 0.1524)
				(type default)
			)
			(layer "B.SilkS")
		)
		(fp_line
			(start -0.7874 0.4064)
			(end 0.7874 0.4064)
			(stroke
				(width 0.1524)
				(type default)
			)
			(layer "B.SilkS")
		)
		(fp_line
			(start -0.7874 -0.4064)
			(end -0.7874 0.4064)
			(stroke
				(width 0.1524)
				(type default)
			)
			(layer "B.SilkS")
		)
		(fp_line
			(start 0.67945 0.3048)
			(end 0.67945 -0.305054)
			(stroke
				(width 0.1)
				(type default)
			)
			(layer "B.Fab")
		)
		(fp_line
			(start 0.67945 -0.305054)
			(end 0.12065 -0.305054)
			(stroke
				(width 0.1)
				(type default)
			)
			(layer "B.Fab")
		)
		(fp_line
			(start 0.12065 0.3048)
			(end 0.67945 0.3048)
			(stroke
				(width 0.1)
				(type default)
			)
			(layer "B.Fab")
		)
		(fp_line
			(start 0.12065 0.2794)
			(end 0.12065 0.3048)
			(stroke
				(width 0.1)
				(type default)
			)
			(layer "B.Fab")
		)
		(fp_line
			(start 0.12065 -0.2794)
			(end -0.12065 -0.2794)
			(stroke
				(width 0.1)
				(type default)
			)
			(layer "B.Fab")
		)
		(fp_line
			(start 0.12065 -0.305054)
			(end 0.12065 -0.2794)
			(stroke
				(width 0.1)
				(type default)
			)
			(layer "B.Fab")
		)
		(fp_line
			(start -0.120396 0.3048)
			(end -0.120396 0.2794)
			(stroke
				(width 0.1)
				(type default)
			)
			(layer "B.Fab")
		)
		(fp_line
			(start -0.120396 0.2794)
			(end 0.12065 0.2794)
			(stroke
				(width 0.1)
				(type default)
			)
			(layer "B.Fab")
		)
		(fp_line
			(start -0.12065 -0.2794)
			(end -0.12065 -0.3048)
			(stroke
				(width 0.1)
				(type default)
			)
			(layer "B.Fab")
		)
		(fp_line
			(start -0.12065 -0.3048)
			(end -0.67945 -0.3048)
			(stroke
				(width 0.1)
				(type default)
			)
			(layer "B.Fab")
		)
		(fp_line
			(start -0.67945 0.3048)
			(end -0.120396 0.3048)
			(stroke
				(width 0.1)
				(type default)
			)
			(layer "B.Fab")
		)
		(fp_line
			(start -0.67945 -0.3048)
			(end -0.67945 0.3048)
			(stroke
				(width 0.1)
				(type default)
			)
			(layer "B.Fab")
		)
		(pad "1" smd circle
			(at 0.40005 0)
			(size 0 0)
			(layers "B.Cu" "B.Mask" "B.Paste")
			(net "PWRGD_CHD_CPU1_DIMM2")
		)
		(pad "2" smd circle
			(at -0.40005 0)
			(size 0 0)
			(layers "B.Cu" "B.Mask" "B.Paste")
			(net "PWRGD_FAIL_CPU1_CD")
		)
	)
	(footprint ""
		(layer "B.Cu")
		(at 189.232286 -193.615056 -90)
		(property "Reference" "R819"
			(at 0 0 90)
			(layer "B.SilkS")
			(hide yes)
			(effects
				(font
					(size 1.27 1.27)
				)
				(justify mirror)
			)
		)
		(property "Value" ""
			(at 0 0 90)
			(layer "B.Fab")
			(effects
				(font
					(size 1.27 1.27)
				)
				(justify mirror)
			)
		)
		(duplicate_pad_numbers_are_jumpers no)
		(fp_line
			(start -0.7874 0.4064)
			(end 0.7874 0.4064)
			(stroke
				(width 0.1524)
				(type default)
			)
			(layer "B.SilkS")
		)
		(fp_line
			(start 0.7874 0.4064)
			(end 0.7874 -0.4064)
			(stroke
				(width 0.1524)
				(type default)
			)
			(layer "B.SilkS")
		)
		(fp_line
			(start -0.7874 -0.4064)
			(end -0.7874 0.4064)
			(stroke
				(width 0.1524)
				(type default)
			)
			(layer "B.SilkS")
		)
		(fp_line
			(start 0.7874 -0.4064)
			(end -0.7874 -0.4064)
			(stroke
				(width 0.1524)
				(type default)
			)
			(layer "B.SilkS")
		)
		(fp_line
			(start -0.67945 0.3048)
			(end -0.120396 0.3048)
			(stroke
				(width 0.1)
				(type default)
			)
			(layer "B.Fab")
		)
		(fp_line
			(start -0.120396 0.3048)
			(end -0.120396 0.2794)
			(stroke
				(width 0.1)
				(type default)
			)
			(layer "B.Fab")
		)
		(fp_line
			(start 0.12065 0.3048)
			(end 0.67945 0.3048)
			(stroke
				(width 0.1)
				(type default)
			)
			(layer "B.Fab")
		)
		(fp_line
			(start 0.67945 0.3048)
			(end 0.67945 -0.305054)
			(stroke
				(width 0.1)
				(type default)
			)
			(layer "B.Fab")
		)
		(fp_line
			(start -0.120396 0.2794)
			(end 0.12065 0.2794)
			(stroke
				(width 0.1)
				(type default)
			)
			(layer "B.Fab")
		)
		(fp_line
			(start 0.12065 0.2794)
			(end 0.12065 0.3048)
			(stroke
				(width 0.1)
				(type default)
			)
			(layer "B.Fab")
		)
		(fp_line
			(start -0.12065 -0.2794)
			(end -0.12065 -0.3048)
			(stroke
				(width 0.1)
				(type default)
			)
			(layer "B.Fab")
		)
		(fp_line
			(start 0.12065 -0.2794)
			(end -0.12065 -0.2794)
			(stroke
				(width 0.1)
				(type default)
			)
			(layer "B.Fab")
		)
		(fp_line
			(start -0.67945 -0.3048)
			(end -0.67945 0.3048)
			(stroke
				(width 0.1)
				(type default)
			)
			(layer "B.Fab")
		)
		(fp_line
			(start -0.12065 -0.3048)
			(end -0.67945 -0.3048)
			(stroke
				(width 0.1)
				(type default)
			)
			(layer "B.Fab")
		)
		(fp_line
			(start 0.12065 -0.305054)
			(end 0.12065 -0.2794)
			(stroke
				(width 0.1)
				(type default)
			)
			(layer "B.Fab")
		)
		(fp_line
			(start 0.67945 -0.305054)
			(end 0.12065 -0.305054)
			(stroke
				(width 0.1)
				(type default)
			)
			(layer "B.Fab")
		)
		(pad "1" smd circle
			(at 0.40005 0 90)
			(size 0 0)
			(layers "B.Cu" "B.Mask" "B.Paste")
			(net "PVCCD_HV_CPU1")
		)
		(pad "2" smd circle
			(at -0.40005 0 90)
			(size 0 0)
			(layers "B.Cu" "B.Mask" "B.Paste")
			(net "RST_M_GH_CPU1_FPGA_N")
		)
	)
	(footprint ""
		(layer "B.Cu")
		(at 391.416032 -337.85048)
		(property "Reference" "C1397"
			(at 0 0 0)
			(layer "B.SilkS")
			(hide yes)
			(effects
				(font
					(size 1.27 1.27)
				)
				(justify mirror)
			)
		)
		(property "Value" ""
			(at 0 0 0)
			(layer "B.Fab")
			(effects
				(font
					(size 1.27 1.27)
				)
				(justify mirror)
			)
		)
		(duplicate_pad_numbers_are_jumpers no)
		(fp_line
			(start -1.524 -0.762)
			(end -1.524 0.762)
			(stroke
				(width 0.1524)
				(type default)
			)
			(layer "B.SilkS")
		)
		(fp_line
			(start -1.524 0.762)
			(end 1.524 0.762)
			(stroke
				(width 0.1524)
				(type default)
			)
			(layer "B.SilkS")
		)
		(fp_line
			(start 1.524 -0.762)
			(end -1.524 -0.762)
			(stroke
				(width 0.1524)
				(type default)
			)
			(layer "B.SilkS")
		)
		(fp_line
			(start 1.524 0.762)
			(end 1.524 -0.762)
			(stroke
				(width 0.1524)
				(type default)
			)
			(layer "B.SilkS")
		)
		(fp_line
			(start -1.1049 -0.724916)
			(end 1.1049 -0.724916)
			(stroke
				(width 0.1)
				(type default)
			)
			(layer "B.Fab")
		)
		(fp_line
			(start -1.1049 0.724916)
			(end -1.1049 -0.724916)
			(stroke
				(width 0.1)
				(type default)
			)
			(layer "B.Fab")
		)
		(fp_line
			(start 1.1049 -0.724916)
			(end 1.1049 0.724916)
			(stroke
				(width 0.1)
				(type default)
			)
			(layer "B.Fab")
		)
		(fp_line
			(start 1.1049 0.724916)
			(end -1.1049 0.724916)
			(stroke
				(width 0.1)
				(type default)
			)
			(layer "B.Fab")
		)
		(pad "1" smd rect
			(at 0.889 0)
			(size 1.016 1.27)
			(layers "B.Cu" "B.Mask" "B.Paste")
			(net "PVPP_HBM_CPU0")
		)
		(pad "2" smd rect
			(at -0.889 0)
			(size 1.016 1.27)
			(layers "B.Cu" "B.Mask" "B.Paste")
			(net "GND")
		)
	)
)
